(kicad_pcb
	(version 20241229)
	(generator "pcbnew")
	(generator_version "9.0")
	(general
		(thickness 1.294)
		(legacy_teardrops no)
	)
	(paper "A3")
	(title_block
		(title "Kintex 410T devboard")
		(date "2024-04-03")
		(rev "1.1.2")
		(comment 9 "footprints 65-70 of 975")
	)
	(layers
		(0 "F.Cu" mixed)
		(4 "In1.Cu" power)
		(6 "In2.Cu" power)
		(8 "In3.Cu" mixed)
		(10 "In4.Cu" power)
		(12 "In5.Cu" mixed)
		(14 "In6.Cu" power)
		(16 "In7.Cu" mixed)
		(18 "In8.Cu" power)
		(2 "B.Cu" mixed)
		(9 "F.Adhes" user "F.Adhesive")
		(11 "B.Adhes" user "B.Adhesive")
		(13 "F.Paste" user)
		(15 "B.Paste" user)
		(5 "F.SilkS" user "F.Silkscreen")
		(7 "B.SilkS" user "B.Silkscreen")
		(1 "F.Mask" user)
		(3 "B.Mask" user)
		(17 "Dwgs.User" user "User.Drawings")
		(19 "Cmts.User" user "User.Comments")
		(21 "Eco1.User" user "User.Eco1")
		(23 "Eco2.User" user "User.Eco2")
		(25 "Edge.Cuts" user)
		(27 "Margin" user)
		(31 "F.CrtYd" user "F.Courtyard")
		(29 "B.CrtYd" user "B.Courtyard")
		(35 "F.Fab" user)
		(33 "B.Fab" user)
	)
	(footprint "antmicro-footprints:C_0805_2012Metric"
		(layer "F.Cu")
		(at 189.5 161.949 -90)
		(descr "Capacitor SMD 0805")
		(tags "capacitor SMD 0805")
		(property "Reference" "C341"
			(at -1.399 2.1 90)
			(layer "F.SilkS")
			(effects
				(font
					(size 0.7 0.7)
					(thickness 0.15)
				)
				(justify right bottom)
			)
		)
		(property "Value" "C_22u_25V_0805"
			(at 0 1.947 90)
			(layer "F.Fab")
			(effects
				(font
					(size 0.7 0.7)
					(thickness 0.15)
				)
				(justify right bottom)
			)
		)
		(property "Description" "SMT Multilayer Ceramic Capacitor, 22uF, +/-20%, 25V, X5R, 0805 [2012 Metric]"
			(at 0 0 270)
			(layer "F.Fab")
			(hide yes)
			(effects
				(font
					(size 1.27 1.27)
					(thickness 0.15)
				)
			)
		)
		(property "Author" "Antmicro"
			(at 27.551 351.449 0)
			(layer "F.Fab")
			(hide yes)
			(effects
				(font
					(size 1 1)
					(thickness 0.15)
				)
			)
		)
		(property "Dielectric" "X5R"
			(at 27.551 351.449 0)
			(layer "F.Fab")
			(hide yes)
			(effects
				(font
					(size 1 1)
					(thickness 0.15)
				)
			)
		)
		(property "License" "Apache-2.0"
			(at 27.551 351.449 0)
			(layer "F.Fab")
			(hide yes)
			(effects
				(font
					(size 1 1)
					(thickness 0.15)
				)
			)
		)
		(property "MPN" "CL21A226MAYNNNE"
			(at 27.551 351.449 0)
			(layer "F.Fab")
			(hide yes)
			(effects
				(font
					(size 1 1)
					(thickness 0.15)
				)
			)
		)
		(property "Manufacturer" "Samsung Electro-Mechanics"
			(at 27.551 351.449 0)
			(layer "F.Fab")
			(hide yes)
			(effects
				(font
					(size 1 1)
					(thickness 0.15)
				)
			)
		)
		(property "Val" "22u"
			(at 27.551 351.449 0)
			(layer "F.Fab")
			(hide yes)
			(effects
				(font
					(size 1 1)
					(thickness 0.15)
				)
			)
		)
		(property "Voltage" "25V"
			(at 27.551 351.449 0)
			(layer "F.Fab")
			(hide yes)
			(effects
				(font
					(size 1 1)
					(thickness 0.15)
				)
			)
		)
		(sheetname "DC-DC Converters")
		(sheetfile "dc-dc.kicad_sch")
		(attr smd)
		(fp_line
			(start -0.3 0.7)
			(end 0.3 0.7)
			(stroke
				(width 0.15)
				(type solid)
			)
			(layer "F.SilkS")
		)
		(fp_line
			(start -0.3 -0.7)
			(end 0.3 -0.7)
			(stroke
				(width 0.15)
				(type solid)
			)
			(layer "F.SilkS")
		)
		(fp_rect
			(start 1.95 -0.9)
			(end -1.95 0.9)
			(stroke
				(width 0.05)
				(type default)
			)
			(fill no)
			(layer "F.CrtYd")
		)
		(fp_rect
			(start -0.95 -0.675)
			(end 0.95 0.675)
			(stroke
				(width 0.15)
				(type solid)
			)
			(fill no)
			(layer "F.Fab")
		)
		(pad "1" smd roundrect
			(at -1.1 0 270)
			(size 1.2 1.3)
			(layers "F.Cu" "F.Mask" "F.Paste")
			(roundrect_rratio 0.25)
			(net 1 "GND")
			(pintype "passive")
		)
		(pad "2" smd roundrect
			(at 1.1 0 270)
			(size 1.2 1.3)
			(layers "F.Cu" "F.Mask" "F.Paste")
			(roundrect_rratio 0.25)
			(net 702 "VDC")
			(pintype "passive")
		)
	)
	(footprint "antmicro-footprints:R_0402_1005Metric"
		(layer "F.Cu")
		(at 264.7 137.6 90)
		(descr "Resistor SMD 0402")
		(tags "resistor SMD 0402")
		(property "Reference" "R151"
			(at 32.3 -29.85 180)
			(layer "F.SilkS")
			(effects
				(font
					(size 0.7 0.7)
					(thickness 0.15)
				)
				(justify left bottom)
			)
		)
		(property "Value" "R_330R_0402"
			(at 0 1.4 90)
			(layer "F.Fab")
			(effects
				(font
					(size 0.7 0.7)
					(thickness 0.15)
				)
				(justify left bottom)
			)
		)
		(property "Description" "SMD Chip Resistor, 330 ohm, ± 1%, 62.5 mW, 0402 [1005 Metric], Thick Film, General Purpose"
			(at 0 0 90)
			(layer "F.Fab")
			(hide yes)
			(effects
				(font
					(size 1.27 1.27)
					(thickness 0.15)
				)
			)
		)
		(property "Author" "Antmicro"
			(at 402.3 -127.1 0)
			(layer "F.Fab")
			(hide yes)
			(effects
				(font
					(size 1 1)
					(thickness 0.15)
				)
			)
		)
		(property "License" "Apache-2.0"
			(at 402.3 -127.1 0)
			(layer "F.Fab")
			(hide yes)
			(effects
				(font
					(size 1 1)
					(thickness 0.15)
				)
			)
		)
		(property "MPN" "CR0402-FX-3300GLF"
			(at 402.3 -127.1 0)
			(layer "F.Fab")
			(hide yes)
			(effects
				(font
					(size 1 1)
					(thickness 0.15)
				)
			)
		)
		(property "Manufacturer" "Bourns"
			(at 402.3 -127.1 0)
			(layer "F.Fab")
			(hide yes)
			(effects
				(font
					(size 1 1)
					(thickness 0.15)
				)
			)
		)
		(property "Tolerance" "1%"
			(at 402.3 -127.1 0)
			(layer "F.Fab")
			(hide yes)
			(effects
				(font
					(size 1 1)
					(thickness 0.15)
				)
			)
		)
		(property "Val" "330R"
			(at 402.3 -127.1 0)
			(layer "F.Fab")
			(hide yes)
			(effects
				(font
					(size 1 1)
					(thickness 0.15)
				)
			)
		)
		(sheetname "USB PHY")
		(sheetfile "usb-phy.kicad_sch")
		(attr smd)
		(fp_rect
			(start -0.925 -0.47)
			(end 0.925 0.47)
			(stroke
				(width 0.05)
				(type default)
			)
			(fill no)
			(layer "F.CrtYd")
		)
		(fp_rect
			(start -0.5 -0.25)
			(end 0.5 0.25)
			(stroke
				(width 0.15)
				(type solid)
			)
			(fill no)
			(layer "F.Fab")
		)
		(pad "1" smd roundrect
			(at -0.48 0 90)
			(size 0.59 0.64)
			(layers "F.Cu" "F.Mask" "F.Paste")
			(roundrect_rratio 0.25)
			(net 791 "Net-(D27-A)")
			(pintype "passive")
		)
		(pad "2" smd roundrect
			(at 0.48 0 90)
			(size 0.59 0.64)
			(layers "F.Cu" "F.Mask" "F.Paste")
			(roundrect_rratio 0.25)
			(net 913 "/USB PHY/LED_RX0")
			(pintype "passive")
		)
	)
	(footprint "antmicro-footprints:C_0402_1005Metric"
		(layer "F.Cu")
		(at 173.570001 114.096251 180)
		(descr "Capacitor SMD 0402")
		(tags "capacitor SMD 0402")
		(property "Reference" "C303"
			(at -3.729999 -0.356249 0)
			(layer "F.SilkS")
			(effects
				(font
					(size 0.7 0.7)
					(thickness 0.15)
				)
				(justify right bottom)
			)
		)
		(property "Value" "C_100n_0402"
			(at 0 1.4 0)
			(layer "F.Fab")
			(effects
				(font
					(size 0.7 0.7)
					(thickness 0.15)
				)
				(justify right bottom)
			)
		)
		(property "Description" "SMD Multilayer Ceramic Capacitor, 0.1 µF, 50 V, 0402 [1005 Metric], ± 10%, X5R, GRM Series"
			(at 0 0 180)
			(layer "F.Fab")
			(hide yes)
			(effects
				(font
					(size 1.27 1.27)
					(thickness 0.15)
				)
			)
		)
		(property "Author" "Antmicro"
			(at 347.140002 228.192502 0)
			(layer "F.Fab")
			(hide yes)
			(effects
				(font
					(size 1 1)
					(thickness 0.15)
				)
			)
		)
		(property "Dielectric" "X5R"
			(at 347.140002 228.192502 0)
			(layer "F.Fab")
			(hide yes)
			(effects
				(font
					(size 1 1)
					(thickness 0.15)
				)
			)
		)
		(property "License" "Apache-2.0"
			(at 347.140002 228.192502 0)
			(layer "F.Fab")
			(hide yes)
			(effects
				(font
					(size 1 1)
					(thickness 0.15)
				)
			)
		)
		(property "MPN" "GRM155R61H104KE14D"
			(at 347.140002 228.192502 0)
			(layer "F.Fab")
			(hide yes)
			(effects
				(font
					(size 1 1)
					(thickness 0.15)
				)
			)
		)
		(property "Manufacturer" "Murata"
			(at 347.140002 228.192502 0)
			(layer "F.Fab")
			(hide yes)
			(effects
				(font
					(size 1 1)
					(thickness 0.15)
				)
			)
		)
		(property "Val" "100n"
			(at 347.140002 228.192502 0)
			(layer "F.Fab")
			(hide yes)
			(effects
				(font
					(size 1 1)
					(thickness 0.15)
				)
			)
		)
		(property "Voltage" "50V"
			(at 347.140002 228.192502 0)
			(layer "F.Fab")
			(hide yes)
			(effects
				(font
					(size 1 1)
					(thickness 0.15)
				)
			)
		)
		(sheetname "FMC+ HSPC")
		(sheetfile "fmc-hspc.kicad_sch")
		(attr smd)
		(fp_rect
			(start -0.925 -0.47)
			(end 0.925 0.47)
			(stroke
				(width 0.05)
				(type default)
			)
			(fill no)
			(layer "F.CrtYd")
		)
		(fp_line
			(start 0.504 0.248)
			(end -0.494 0.248)
			(stroke
				(width 0.15)
				(type solid)
			)
			(layer "F.Fab")
		)
		(fp_line
			(start 0.504 -0.25)
			(end 0.504 0.248)
			(stroke
				(width 0.15)
				(type solid)
			)
			(layer "F.Fab")
		)
		(fp_line
			(start -0.494 0.248)
			(end -0.494 -0.25)
			(stroke
				(width 0.15)
				(type solid)
			)
			(layer "F.Fab")
		)
		(fp_line
			(start -0.494 -0.25)
			(end 0.504 -0.25)
			(stroke
				(width 0.15)
				(type solid)
			)
			(layer "F.Fab")
		)
		(pad "1" smd roundrect
			(at -0.48 0 180)
			(size 0.59 0.64)
			(layers "F.Cu" "F.Mask" "F.Paste")
			(roundrect_rratio 0.25)
			(net 78 "/FMC+ HSPC/GTX116.TX1_N")
			(pintype "passive")
		)
		(pad "2" smd roundrect
			(at 0.48 0 180)
			(size 0.59 0.64)
			(layers "F.Cu" "F.Mask" "F.Paste")
			(roundrect_rratio 0.25)
			(net 76 "/FMC+ HSPC/GTX_TX2_C_N")
			(pintype "passive")
		)
	)
	(footprint "antmicro-footprints:R_0402_1005Metric"
		(layer "F.Cu")
		(at 254.445 133.835)
		(descr "Resistor SMD 0402")
		(tags "resistor SMD 0402")
		(property "Reference" "R159"
			(at -1.395 -3.935 0)
			(layer "F.SilkS")
			(effects
				(font
					(size 0.7 0.7)
					(thickness 0.15)
				)
				(justify left bottom)
			)
		)
		(property "Value" "R_10k_0402"
			(at 0 1.4 0)
			(layer "F.Fab")
			(effects
				(font
					(size 0.7 0.7)
					(thickness 0.15)
				)
				(justify left bottom)
			)
		)
		(property "Description" "SMD Chip Resistor, 10 kohm, ± 1%, 62.5 mW, 0402 [1005 Metric], Thick Film, General Purpose"
			(at 0 0 0)
			(layer "F.Fab")
			(hide yes)
			(effects
				(font
					(size 1.27 1.27)
					(thickness 0.15)
				)
			)
		)
		(property "Author" "Antmicro"
			(at 0 0 0)
			(layer "F.Fab")
			(hide yes)
			(effects
				(font
					(size 1 1)
					(thickness 0.15)
				)
			)
		)
		(property "License" "Apache-2.0"
			(at 0 0 0)
			(layer "F.Fab")
			(hide yes)
			(effects
				(font
					(size 1 1)
					(thickness 0.15)
				)
			)
		)
		(property "MPN" "CR0402-FX-1002GLF"
			(at 0 0 0)
			(layer "F.Fab")
			(hide yes)
			(effects
				(font
					(size 1 1)
					(thickness 0.15)
				)
			)
		)
		(property "Manufacturer" "Bourns"
			(at 0 0 0)
			(layer "F.Fab")
			(hide yes)
			(effects
				(font
					(size 1 1)
					(thickness 0.15)
				)
			)
		)
		(property "Tolerance" "1%"
			(at 0 0 0)
			(layer "F.Fab")
			(hide yes)
			(effects
				(font
					(size 1 1)
					(thickness 0.15)
				)
			)
		)
		(property "Val" "10k"
			(at 0 0 0)
			(layer "F.Fab")
			(hide yes)
			(effects
				(font
					(size 1 1)
					(thickness 0.15)
				)
			)
		)
		(sheetname "USB PHY")
		(sheetfile "usb-phy.kicad_sch")
		(attr smd)
		(fp_rect
			(start -0.925 -0.47)
			(end 0.925 0.47)
			(stroke
				(width 0.05)
				(type default)
			)
			(fill no)
			(layer "F.CrtYd")
		)
		(fp_rect
			(start -0.5 -0.25)
			(end 0.5 0.25)
			(stroke
				(width 0.15)
				(type solid)
			)
			(fill no)
			(layer "F.Fab")
		)
		(pad "1" smd roundrect
			(at -0.48 0)
			(size 0.59 0.64)
			(layers "F.Cu" "F.Mask" "F.Paste")
			(roundrect_rratio 0.25)
			(net 919 "/USB PHY/FTDI_RST")
			(pintype "passive")
		)
		(pad "2" smd roundrect
			(at 0.48 0)
			(size 0.59 0.64)
			(layers "F.Cu" "F.Mask" "F.Paste")
			(roundrect_rratio 0.25)
			(net 707 "/USB PHY/FTDI_3V3")
			(pintype "passive")
		)
	)
	(footprint "antmicro-footprints:C_0603_1608Metric"
		(layer "F.Cu")
		(at 186.525 184.373999 -90)
		(descr "Capacitor SMD 0603")
		(tags "capacitor 0603")
		(property "Reference" "C206"
			(at -1.073999 0.575 90)
			(layer "F.SilkS")
			(effects
				(font
					(size 0.7 0.7)
					(thickness 0.15)
				)
				(justify right bottom)
			)
		)
		(property "Value" "C_1u_25V_0603"
			(at 0 1.6 90)
			(layer "F.Fab")
			(effects
				(font
					(size 0.7 0.7)
					(thickness 0.15)
				)
				(justify right bottom)
			)
		)
		(property "Description" "SMD Multilayer Ceramic Capacitor, 1 µF, 25 V, 0603 [1608 Metric], ± 10%, X5R, CL"
			(at 0 0 270)
			(layer "F.Fab")
			(hide yes)
			(effects
				(font
					(size 1.27 1.27)
					(thickness 0.15)
				)
			)
		)
		(property "Author" "Antmicro"
			(at 2.151001 370.898999 0)
			(layer "F.Fab")
			(hide yes)
			(effects
				(font
					(size 1 1)
					(thickness 0.15)
				)
			)
		)
		(property "Dielectric" ""
			(at 2.151001 370.898999 0)
			(layer "F.Fab")
			(hide yes)
			(effects
				(font
					(size 1 1)
					(thickness 0.15)
				)
			)
		)
		(property "License" "Apache-2.0"
			(at 2.151001 370.898999 0)
			(layer "F.Fab")
			(hide yes)
			(effects
				(font
					(size 1 1)
					(thickness 0.15)
				)
			)
		)
		(property "MPN" "CL10A105KA8NNNC"
			(at 2.151001 370.898999 0)
			(layer "F.Fab")
			(hide yes)
			(effects
				(font
					(size 1 1)
					(thickness 0.15)
				)
			)
		)
		(property "Manufacturer" "Samsung Electro-Mechanics"
			(at 2.151001 370.898999 0)
			(layer "F.Fab")
			(hide yes)
			(effects
				(font
					(size 1 1)
					(thickness 0.15)
				)
			)
		)
		(property "Val" "1u"
			(at 2.151001 370.898999 0)
			(layer "F.Fab")
			(hide yes)
			(effects
				(font
					(size 1 1)
					(thickness 0.15)
				)
			)
		)
		(property "Voltage" "25V"
			(at 2.151001 370.898999 0)
			(layer "F.Fab")
			(hide yes)
			(effects
				(font
					(size 1 1)
					(thickness 0.15)
				)
			)
		)
		(sheetname "Power supply")
		(sheetfile "power-supply.kicad_sch")
		(attr smd)
		(fp_line
			(start -0.15 0.4)
			(end 0.15 0.4)
			(stroke
				(width 0.15)
				(type solid)
			)
			(layer "F.SilkS")
		)
		(fp_line
			(start -0.15 -0.4)
			(end 0.15 -0.4)
			(stroke
				(width 0.15)
				(type solid)
			)
			(layer "F.SilkS")
		)
		(fp_rect
			(start -1.25 -0.65)
			(end 1.25 0.65)
			(stroke
				(width 0.05)
				(type solid)
			)
			(fill no)
			(layer "F.CrtYd")
		)
		(fp_rect
			(start -0.8 -0.4)
			(end 0.8 0.4)
			(stroke
				(width 0.15)
				(type solid)
			)
			(fill no)
			(layer "F.Fab")
		)
		(pad "1" smd roundrect
			(at -0.7 0 270)
			(size 0.8 1)
			(layers "F.Cu" "F.Mask" "F.Paste")
			(roundrect_rratio 0.2)
			(net 1 "GND")
			(pintype "passive")
		)
		(pad "2" smd roundrect
			(at 0.7 0 270)
			(size 0.8 1)
			(layers "F.Cu" "F.Mask" "F.Paste")
			(roundrect_rratio 0.2)
			(net 702 "VDC")
			(pintype "passive")
		)
	)
	(footprint "antmicro-footprints:LED_0603_1608Metric_G"
		(layer "F.Cu")
		(at 266.6 135.4 180)
		(descr "LED SMD 0603 Green")
		(tags "LED SMD 0603 Green")
		(property "Reference" "D28"
			(at -0.85 -1.6 0)
			(layer "F.SilkS")
			(effects
				(font
					(size 0.7 0.7)
					(thickness 0.15)
				)
				(justify right bottom)
			)
		)
		(property "Value" "LED_G_0603_KP-1608CGCK"
			(at 0 1.6 0)
			(layer "F.Fab")
			(effects
				(font
					(size 0.7 0.7)
					(thickness 0.15)
				)
				(justify right bottom)
			)
		)
		(property "Description" "LED, Green, SMD, 0603, 20 mA, 2.1 V, 570 nm"
			(at 0 0 180)
			(layer "F.Fab")
			(hide yes)
			(effects
				(font
					(size 1.27 1.27)
					(thickness 0.15)
				)
			)
		)
		(property "Author" "Antmicro"
			(at 533.2 270.8 0)
			(layer "F.Fab")
			(hide yes)
			(effects
				(font
					(size 1 1)
					(thickness 0.15)
				)
			)
		)
		(property "Color" "Green"
			(at 533.2 270.8 0)
			(layer "F.Fab")
			(hide yes)
			(effects
				(font
					(size 1 1)
					(thickness 0.15)
				)
			)
		)
		(property "License" "Apache-2.0"
			(at 533.2 270.8 0)
			(layer "F.Fab")
			(hide yes)
			(effects
				(font
					(size 1 1)
					(thickness 0.15)
				)
			)
		)
		(property "MPN" "KP-1608CGCK"
			(at 533.2 270.8 0)
			(layer "F.Fab")
			(hide yes)
			(effects
				(font
					(size 1 1)
					(thickness 0.15)
				)
			)
		)
		(property "Manufacturer" "Kingbright"
			(at 533.2 270.8 0)
			(layer "F.Fab")
			(hide yes)
			(effects
				(font
					(size 1 1)
					(thickness 0.15)
				)
			)
		)
		(sheetname "USB PHY")
		(sheetfile "usb-phy.kicad_sch")
		(attr smd)
		(fp_line
			(start 0.22 0.35)
			(end -0.22 0.35)
			(stroke
				(width 0.15)
				(type solid)
			)
			(layer "F.SilkS")
		)
		(fp_line
			(start 0.22 -0.35)
			(end -0.22 -0.35)
			(stroke
				(width 0.15)
				(type solid)
			)
			(layer "F.SilkS")
		)
		(fp_line
			(start 0.105328 0.201008)
			(end 0.105328 -0.198992)
			(stroke
				(width 0.1)
				(type solid)
			)
			(layer "F.SilkS")
		)
		(fp_line
			(start 0.105328 0.201008)
			(end -0.094672 0.001008)
			(stroke
				(width 0.1)
				(type solid)
			)
			(layer "F.SilkS")
		)
		(fp_line
			(start 0.105328 0.001008)
			(end 0.24 0.001)
			(stroke
				(width 0.1)
				(type solid)
			)
			(layer "F.SilkS")
		)
		(fp_line
			(start -0.094672 0.201008)
			(end -0.094672 -0.198992)
			(stroke
				(width 0.1)
				(type solid)
			)
			(layer "F.SilkS")
		)
		(fp_line
			(start -0.094672 0.001008)
			(end 0.105328 -0.198992)
			(stroke
				(width 0.1)
				(type solid)
			)
			(layer "F.SilkS")
		)
		(fp_line
			(start -0.094672 0.001008)
			(end -0.24 0.001008)
			(stroke
				(width 0.1)
				(type solid)
			)
			(layer "F.SilkS")
		)
		(fp_line
			(start -1.18 -0.319)
			(end -1.18 0.321)
			(stroke
				(width 0.15)
				(type solid)
			)
			(layer "F.SilkS")
		)
		(fp_rect
			(start 1.25 0.65)
			(end -1.25 -0.65)
			(stroke
				(width 0.05)
				(type solid)
			)
			(fill no)
			(layer "F.CrtYd")
		)
		(fp_line
			(start 0.599 0)
			(end 0.201 0)
			(stroke
				(width 0.15)
				(type solid)
			)
			(layer "F.Fab")
		)
		(fp_line
			(start 0.201 0.2)
			(end 0.201 0)
			(stroke
				(width 0.15)
				(type solid)
			)
			(layer "F.Fab")
		)
		(fp_line
			(start 0.201 0)
			(end 0.201 -0.202)
			(stroke
				(width 0.15)
				(type solid)
			)
			(layer "F.Fab")
		)
		(fp_line
			(start 0.201 -0.202)
			(end -0.101 0)
			(stroke
				(width 0.15)
				(type solid)
			)
			(layer "F.Fab")
		)
		(fp_line
			(start -0.101 0)
			(end 0.201 0.2)
			(stroke
				(width 0.15)
				(type solid)
			)
			(layer "F.Fab")
		)
		(fp_line
			(start -0.199 0.2)
			(end -0.199 0.1)
			(stroke
				(width 0.15)
				(type solid)
			)
			(layer "F.Fab")
		)
		(fp_line
			(start -0.199 0)
			(end -0.597 0)
			(stroke
				(width 0.15)
				(type solid)
			)
			(layer "F.Fab")
		)
		(fp_line
			(start -0.199 -0.202)
			(end -0.199 0.1)
			(stroke
				(width 0.15)
				(type solid)
			)
			(layer "F.Fab")
		)
		(fp_rect
			(start 0.848 0.4)
			(end -0.85 -0.402)
			(stroke
				(width 0.15)
				(type solid)
			)
			(fill no)
			(layer "F.Fab")
		)
		(pad "1" smd roundrect
			(at -0.7 0)
			(size 0.8 1)
			(layers "F.Cu" "F.Mask" "F.Paste")
			(roundrect_rratio 0.2)
			(net 1 "GND")
			(pinfunction "C")
			(pintype "passive")
		)
		(pad "2" smd roundrect
			(at 0.7 0)
			(size 0.8 1)
			(layers "F.Cu" "F.Mask" "F.Paste")
			(roundrect_rratio 0.2)
			(net 792 "Net-(D28-A)")
			(pinfunction "A")
			(pintype "passive")
		)
	)
)
